(kicad_pcb
	(version 20241229)
	(generator "pcbnew")
	(generator_version "9.0")
	(general
		(thickness 1.711)
		(legacy_teardrops no)
	)
	(paper "A4")
	(title_block
		(title "Antmicro Baseboard for Jetson AGX Thor")
		(date "2026-02-18")
		(rev "1.1.0")
		(company "Antmicro Ltd")
		(comment 1 "www.antmicro.com")
		(comment 9 "footprints 1078-1082 of 1170")
	)
	(layers
		(0 "F.Cu" signal)
		(4 "In1.Cu" signal)
		(6 "In2.Cu" signal)
		(8 "In3.Cu" signal)
		(10 "In4.Cu" jumper)
		(12 "In5.Cu" signal)
		(14 "In6.Cu" signal)
		(16 "In7.Cu" signal)
		(18 "In8.Cu" signal)
		(2 "B.Cu" signal)
		(9 "F.Adhes" user "F.Adhesive")
		(11 "B.Adhes" user "B.Adhesive")
		(13 "F.Paste" user)
		(15 "B.Paste" user)
		(5 "F.SilkS" user "F.Silkscreen")
		(7 "B.SilkS" user "B.Silkscreen")
		(1 "F.Mask" user)
		(3 "B.Mask" user)
		(17 "Dwgs.User" user "User.Drawings")
		(19 "Cmts.User" user "User.Comments")
		(21 "Eco1.User" user "User.Eco1")
		(23 "Eco2.User" user "User.Eco2")
		(25 "Edge.Cuts" user)
		(27 "Margin" user)
		(31 "F.CrtYd" user "F.Courtyard")
		(29 "B.CrtYd" user "B.Courtyard")
		(35 "F.Fab" user)
		(33 "B.Fab" user)
	)
	(footprint "antmicro-footprints:R_0402_1005Metric"
		(layer "B.Cu")
		(at 187.8 121.7 90)
		(descr "Resistor SMD 0402")
		(tags "resistor SMD 0402")
		(property "Reference" "R386"
			(at -3.7 -0.4 90)
			(layer "B.SilkS")
			(effects
				(font
					(size 0.7 0.7)
					(thickness 0.15)
				)
				(justify right top mirror)
			)
		)
		(property "Value" "R_0R_0402"
			(at -1.011843 -1.772047 90)
			(layer "B.Fab")
			(effects
				(font
					(size 0.7 0.7)
					(thickness 0.15)
				)
				(justify right top mirror)
			)
		)
		(property "Datasheet" "https://industrial.panasonic.com/cdbs/www-data/pdf/RDA0000/AOA0000C301.pdf"
			(at 0 0 90)
			(layer "B.Fab")
			(hide yes)
			(effects
				(font
					(size 1.27 1.27)
					(thickness 0.15)
				)
				(justify mirror)
			)
		)
		(property "Description" "SMD Chip Resistor, Jumper, 0 ohm, 100 mW, 0402 [1005 Metric], Thick Film, General Purpose"
			(at 0 0 90)
			(layer "B.Fab")
			(hide yes)
			(effects
				(font
					(size 1.27 1.27)
					(thickness 0.15)
				)
				(justify mirror)
			)
		)
		(property "MPN" "ERJ2GE0R00X"
			(at 0 0 270)
			(unlocked yes)
			(layer "B.Fab")
			(hide yes)
			(effects
				(font
					(size 1 1)
					(thickness 0.15)
				)
				(justify mirror)
			)
		)
		(property "Manufacturer" "Panasonic"
			(at 0 0 270)
			(unlocked yes)
			(layer "B.Fab")
			(hide yes)
			(effects
				(font
					(size 1 1)
					(thickness 0.15)
				)
				(justify mirror)
			)
		)
		(property "License" "Apache-2.0"
			(at 0 0 270)
			(unlocked yes)
			(layer "B.Fab")
			(hide yes)
			(effects
				(font
					(size 1 1)
					(thickness 0.15)
				)
				(justify mirror)
			)
		)
		(property "Author" "Antmicro"
			(at 0 0 270)
			(unlocked yes)
			(layer "B.Fab")
			(hide yes)
			(effects
				(font
					(size 1 1)
					(thickness 0.15)
				)
				(justify mirror)
			)
		)
		(property "Val" "0R"
			(at 0 0 270)
			(unlocked yes)
			(layer "B.Fab")
			(hide yes)
			(effects
				(font
					(size 1 1)
					(thickness 0.15)
				)
				(justify mirror)
			)
		)
		(property "Tolerance" "~"
			(at 0 0 270)
			(unlocked yes)
			(layer "B.Fab")
			(hide yes)
			(effects
				(font
					(size 1 1)
					(thickness 0.15)
				)
				(justify mirror)
			)
		)
		(property "Current" "1A"
			(at 0 0 270)
			(unlocked yes)
			(layer "B.Fab")
			(hide yes)
			(effects
				(font
					(size 1 1)
					(thickness 0.15)
				)
				(justify mirror)
			)
		)
		(sheetname "/USB Debug, PD/")
		(sheetfile "usb_debug_pd.kicad_sch")
		(attr smd exclude_from_pos_files exclude_from_bom dnp)
		(fp_rect
			(start -0.925 0.47)
			(end 0.925 -0.47)
			(stroke
				(width 0.05)
				(type default)
			)
			(fill no)
			(layer "B.CrtYd")
		)
		(fp_rect
			(start -0.5 0.25)
			(end 0.5 -0.25)
			(stroke
				(width 0.15)
				(type solid)
			)
			(fill no)
			(layer "B.Fab")
		)
		(fp_text user "Author: Antmicro"
			(at -0.95 -4.169 90)
			(layer "B.Fab")
			(effects
				(font
					(size 0.7 0.7)
					(thickness 0.15)
				)
				(justify right top mirror)
			)
		)
		(fp_text user "${REFERENCE}"
			(at -0.95 -3.168 90)
			(layer "B.Fab")
			(effects
				(font
					(size 0.7 0.7)
					(thickness 0.15)
				)
				(justify right top mirror)
			)
		)
		(fp_text user "License: Apache-2.0"
			(at -0.95 -5.169 90)
			(layer "B.Fab")
			(effects
				(font
					(size 0.7 0.7)
					(thickness 0.15)
				)
				(justify right top mirror)
			)
		)
		(pad "1" smd roundrect
			(at -0.48 0 90)
			(size 0.59 0.64)
			(layers "B.Cu" "B.Mask" "B.Paste")
			(roundrect_rratio 0.25)
			(net 810 "/USB Debug, PD/MISO")
			(pintype "passive")
		)
		(pad "2" smd roundrect
			(at 0.48 0 90)
			(size 0.59 0.64)
			(layers "B.Cu" "B.Mask" "B.Paste")
			(roundrect_rratio 0.25)
			(net 923 "/USB Debug, PD/SPI_{HUB_DEBUG}.MISO")
			(pintype "passive")
		)
	)
	(footprint "antmicro-footprints:R_0402_1005Metric"
		(layer "B.Cu")
		(at 71.1 64.3)
		(descr "Resistor SMD 0402")
		(tags "resistor SMD 0402")
		(property "Reference" "R398"
			(at 0.9 -0.3 0)
			(layer "B.SilkS")
			(effects
				(font
					(size 0.7 0.7)
					(thickness 0.15)
				)
				(justify right top mirror)
			)
		)
		(property "Value" "R_0R_0402"
			(at -1.011843 -1.772047 0)
			(layer "B.Fab")
			(effects
				(font
					(size 0.7 0.7)
					(thickness 0.15)
				)
				(justify right top mirror)
			)
		)
		(property "Datasheet" "https://industrial.panasonic.com/cdbs/www-data/pdf/RDA0000/AOA0000C301.pdf"
			(at 0 0 0)
			(layer "B.Fab")
			(hide yes)
			(effects
				(font
					(size 1.27 1.27)
					(thickness 0.15)
				)
				(justify mirror)
			)
		)
		(property "Description" "SMD Chip Resistor, Jumper, 0 ohm, 100 mW, 0402 [1005 Metric], Thick Film, General Purpose"
			(at 0 0 0)
			(layer "B.Fab")
			(hide yes)
			(effects
				(font
					(size 1.27 1.27)
					(thickness 0.15)
				)
				(justify mirror)
			)
		)
		(property "MPN" "ERJ2GE0R00X"
			(at 0 0 180)
			(unlocked yes)
			(layer "B.Fab")
			(hide yes)
			(effects
				(font
					(size 1 1)
					(thickness 0.15)
				)
				(justify mirror)
			)
		)
		(property "Manufacturer" "Panasonic"
			(at 0 0 180)
			(unlocked yes)
			(layer "B.Fab")
			(hide yes)
			(effects
				(font
					(size 1 1)
					(thickness 0.15)
				)
				(justify mirror)
			)
		)
		(property "License" "Apache-2.0"
			(at 0 0 180)
			(unlocked yes)
			(layer "B.Fab")
			(hide yes)
			(effects
				(font
					(size 1 1)
					(thickness 0.15)
				)
				(justify mirror)
			)
		)
		(property "Author" "Antmicro"
			(at 0 0 180)
			(unlocked yes)
			(layer "B.Fab")
			(hide yes)
			(effects
				(font
					(size 1 1)
					(thickness 0.15)
				)
				(justify mirror)
			)
		)
		(property "Val" "0R"
			(at 0 0 180)
			(unlocked yes)
			(layer "B.Fab")
			(hide yes)
			(effects
				(font
					(size 1 1)
					(thickness 0.15)
				)
				(justify mirror)
			)
		)
		(property "Tolerance" "~"
			(at 0 0 180)
			(unlocked yes)
			(layer "B.Fab")
			(hide yes)
			(effects
				(font
					(size 1 1)
					(thickness 0.15)
				)
				(justify mirror)
			)
		)
		(property "Current" "1A"
			(at 0 0 180)
			(unlocked yes)
			(layer "B.Fab")
			(hide yes)
			(effects
				(font
					(size 1 1)
					(thickness 0.15)
				)
				(justify mirror)
			)
		)
		(sheetname "/CSI/")
		(sheetfile "csi.kicad_sch")
		(attr smd)
		(fp_rect
			(start -0.925 0.47)
			(end 0.925 -0.47)
			(stroke
				(width 0.05)
				(type default)
			)
			(fill no)
			(layer "B.CrtYd")
		)
		(fp_rect
			(start -0.5 0.25)
			(end 0.5 -0.25)
			(stroke
				(width 0.15)
				(type solid)
			)
			(fill no)
			(layer "B.Fab")
		)
		(fp_text user "License: Apache-2.0"
			(at -0.95 -5.169 0)
			(layer "B.Fab")
			(effects
				(font
					(size 0.7 0.7)
					(thickness 0.15)
				)
				(justify right top mirror)
			)
		)
		(fp_text user "${REFERENCE}"
			(at -0.95 -3.168 0)
			(layer "B.Fab")
			(effects
				(font
					(size 0.7 0.7)
					(thickness 0.15)
				)
				(justify right top mirror)
			)
		)
		(fp_text user "Author: Antmicro"
			(at -0.95 -4.169 0)
			(layer "B.Fab")
			(effects
				(font
					(size 0.7 0.7)
					(thickness 0.15)
				)
				(justify right top mirror)
			)
		)
		(pad "1" smd roundrect
			(at -0.48 0)
			(size 0.59 0.64)
			(layers "B.Cu" "B.Mask" "B.Paste")
			(roundrect_rratio 0.25)
			(net 992 "/CSI/SCL_CAM3")
			(pintype "passive")
		)
		(pad "2" smd roundrect
			(at 0.48 0)
			(size 0.59 0.64)
			(layers "B.Cu" "B.Mask" "B.Paste")
			(roundrect_rratio 0.25)
			(net 938 "Net-(J10-Pad42)")
			(pintype "passive")
		)
	)
	(footprint "antmicro-footprints:R_0402_1005Metric"
		(layer "B.Cu")
		(at 207 66.95 180)
		(descr "Resistor SMD 0402")
		(tags "resistor SMD 0402")
		(property "Reference" "R174"
			(at 1.069 -0.304 0)
			(layer "B.SilkS")
			(effects
				(font
					(size 0.7 0.7)
					(thickness 0.15)
				)
				(justify left bottom mirror)
			)
		)
		(property "Value" "R_10k_0402"
			(at -1.011843 -1.772046 0)
			(layer "B.Fab")
			(effects
				(font
					(size 0.7 0.7)
					(thickness 0.15)
				)
				(justify left bottom mirror)
			)
		)
		(property "Datasheet" "https://www.bourns.com/docs/product-datasheets/cr.pdf"
			(at 0 0 0)
			(layer "B.Fab")
			(hide yes)
			(effects
				(font
					(size 1.27 1.27)
					(thickness 0.15)
				)
				(justify mirror)
			)
		)
		(property "Description" "SMD Chip Resistor, 10 kohm, ± 1%, 62.5 mW, 0402 [1005 Metric], Thick Film, General Purpose"
			(at 0 0 0)
			(layer "B.Fab")
			(hide yes)
			(effects
				(font
					(size 1.27 1.27)
					(thickness 0.15)
				)
				(justify mirror)
			)
		)
		(property "Manufacturer" "Bourns"
			(at 0 0 0)
			(unlocked yes)
			(layer "B.Fab")
			(hide yes)
			(effects
				(font
					(size 1 1)
					(thickness 0.15)
				)
				(justify mirror)
			)
		)
		(property "MPN" "CR0402-FX-1002GLF"
			(at 0 0 0)
			(unlocked yes)
			(layer "B.Fab")
			(hide yes)
			(effects
				(font
					(size 1 1)
					(thickness 0.15)
				)
				(justify mirror)
			)
		)
		(property "Val" "10k"
			(at 0 0 0)
			(unlocked yes)
			(layer "B.Fab")
			(hide yes)
			(effects
				(font
					(size 1 1)
					(thickness 0.15)
				)
				(justify mirror)
			)
		)
		(property "License" "Apache-2.0"
			(at 0 0 0)
			(unlocked yes)
			(layer "B.Fab")
			(hide yes)
			(effects
				(font
					(size 1 1)
					(thickness 0.15)
				)
				(justify mirror)
			)
		)
		(property "Author" "Antmicro"
			(at 0 0 0)
			(unlocked yes)
			(layer "B.Fab")
			(hide yes)
			(effects
				(font
					(size 1 1)
					(thickness 0.15)
				)
				(justify mirror)
			)
		)
		(property "Tolerance" "1%"
			(at 0 0 0)
			(unlocked yes)
			(layer "B.Fab")
			(hide yes)
			(effects
				(font
					(size 1 1)
					(thickness 0.15)
				)
				(justify mirror)
			)
		)
		(sheetname "/CSI/")
		(sheetfile "csi.kicad_sch")
		(attr smd exclude_from_pos_files exclude_from_bom dnp)
		(fp_poly
			(pts
				(xy -0.925 0.47) (xy -0.925 -0.47) (xy 0.925 -0.47) (xy 0.925 0.47)
			)
			(stroke
				(width 0.05)
				(type default)
			)
			(fill no)
			(layer "B.CrtYd")
		)
		(fp_poly
			(pts
				(xy -0.5 0.25) (xy -0.5 -0.25) (xy 0.5 -0.25) (xy 0.5 0.25)
			)
			(stroke
				(width 0.15)
				(type solid)
			)
			(fill no)
			(layer "B.Fab")
		)
		(fp_text user "${REFERENCE}"
			(at -0.95 -3.168 0)
			(layer "B.Fab")
			(effects
				(font
					(size 0.7 0.7)
					(thickness 0.15)
				)
				(justify left bottom mirror)
			)
		)
		(fp_text user "Author: Antmicro"
			(at -0.95 -4.169 0)
			(layer "B.Fab")
			(effects
				(font
					(size 0.7 0.7)
					(thickness 0.15)
				)
				(justify left bottom mirror)
			)
		)
		(fp_text user "License: Apache-2.0"
			(at -0.949999 -5.169 0)
			(layer "B.Fab")
			(effects
				(font
					(size 0.7 0.7)
					(thickness 0.15)
				)
				(justify left bottom mirror)
			)
		)
		(pad "1" smd roundrect
			(at -0.48 0 180)
			(size 0.59 0.64)
			(layers "B.Cu" "B.Mask" "B.Paste")
			(roundrect_rratio 0.25)
			(net 123 "/CSI/CAM_CTRL.CSIB_PEN")
			(pintype "passive")
		)
		(pad "2" smd roundrect
			(at 0.48 0 180)
			(size 0.59 0.64)
			(layers "B.Cu" "B.Mask" "B.Paste")
			(roundrect_rratio 0.25)
			(net 2 "+3V3")
			(pintype "passive")
		)
	)
	(footprint "antmicro-footprints:TP_SMD_0.75mm"
		(layer "B.Cu")
		(at 63 74.8 -90)
		(property "Reference" "TP110"
			(at -0.7 -1.5 270)
			(layer "B.SilkS")
			(effects
				(font
					(size 0.7 0.7)
					(thickness 0.15)
				)
				(justify left bottom mirror)
			)
		)
		(property "Value" "TP_0.75mm_SMD"
			(at 0 -1.2 90)
			(layer "B.Fab")
			(effects
				(font
					(size 0.7 0.7)
					(thickness 0.15)
				)
				(justify left bottom mirror)
			)
		)
		(property "Description" "SMT test point"
			(at 0 0 90)
			(layer "B.Fab")
			(hide yes)
			(effects
				(font
					(size 1.27 1.27)
					(thickness 0.15)
				)
				(justify mirror)
			)
		)
		(property "MPN" ""
			(at 0 0 90)
			(unlocked yes)
			(layer "B.Fab")
			(hide yes)
			(effects
				(font
					(size 1 1)
					(thickness 0.15)
				)
				(justify mirror)
			)
		)
		(property "Manufacturer" ""
			(at 0 0 90)
			(unlocked yes)
			(layer "B.Fab")
			(hide yes)
			(effects
				(font
					(size 1 1)
					(thickness 0.15)
				)
				(justify mirror)
			)
		)
		(property "Author" "Antmicro"
			(at 0 0 90)
			(unlocked yes)
			(layer "B.Fab")
			(hide yes)
			(effects
				(font
					(size 1 1)
					(thickness 0.15)
				)
				(justify mirror)
			)
		)
		(property "License" "Apache-2.0"
			(at 0 0 90)
			(unlocked yes)
			(layer "B.Fab")
			(hide yes)
			(effects
				(font
					(size 1 1)
					(thickness 0.15)
				)
				(justify mirror)
			)
		)
		(sheetname "/Expansion connector/")
		(sheetfile "expansion_connector.kicad_sch")
		(attr exclude_from_pos_files exclude_from_bom)
		(fp_circle
			(center 0 0)
			(end 0.475 0)
			(stroke
				(width 0.05)
				(type default)
			)
			(fill no)
			(layer "B.CrtYd")
		)
		(fp_text user "${REFERENCE}"
			(at -0.4 -2.7 90)
			(layer "B.Fab")
			(effects
				(font
					(size 0.7 0.7)
					(thickness 0.15)
				)
				(justify left bottom mirror)
			)
		)
		(fp_text user "License: Apache-2.0"
			(at -0.4 -5.101 90)
			(layer "B.Fab")
			(effects
				(font
					(size 0.7 0.7)
					(thickness 0.15)
				)
				(justify left bottom mirror)
			)
		)
		(fp_text user "Author: Antmicro"
			(at -0.4 -3.901 90)
			(layer "B.Fab")
			(effects
				(font
					(size 0.7 0.7)
					(thickness 0.15)
				)
				(justify left bottom mirror)
			)
		)
		(pad "1" smd circle
			(at 0 0 270)
			(size 0.75 0.75)
			(layers "B.Cu" "B.Mask")
			(net 753 "Net-(J18-PadK01)")
			(pinfunction "1")
			(pintype "passive")
		)
	)
	(footprint "antmicro-footprints:C_0402_1005Metric"
		(layer "B.Cu")
		(at 235.694 109.85)
		(descr "Capacitor SMD 0402")
		(tags "capacitor SMD 0402")
		(property "Reference" "C114"
			(at -2.894 3.55 0)
			(layer "B.SilkS")
			(effects
				(font
					(size 0.7 0.7)
					(thickness 0.15)
				)
				(justify right top mirror)
			)
		)
		(property "Value" "C_100n_0402"
			(at -1.022927 -2.155213 0)
			(layer "B.Fab")
			(effects
				(font
					(size 0.7 0.7)
					(thickness 0.15)
				)
				(justify right top mirror)
			)
		)
		(property "Datasheet" "https://www.murata.com/products/productdetail?partno=GRM155R61H104KE14%23"
			(at 0 0 0)
			(layer "B.Fab")
			(hide yes)
			(effects
				(font
					(size 1.27 1.27)
					(thickness 0.15)
				)
				(justify mirror)
			)
		)
		(property "Description" "SMD Multilayer Ceramic Capacitor, 0.1 µF, 50 V, 0402 [1005 Metric], ± 10%, X5R, GRM Series"
			(at 0 0 0)
			(layer "B.Fab")
			(hide yes)
			(effects
				(font
					(size 1.27 1.27)
					(thickness 0.15)
				)
				(justify mirror)
			)
		)
		(property "Manufacturer" "Murata"
			(at 0 0 180)
			(unlocked yes)
			(layer "B.Fab")
			(hide yes)
			(effects
				(font
					(size 1 1)
					(thickness 0.15)
				)
				(justify mirror)
			)
		)
		(property "MPN" "GRM155R61H104KE14D"
			(at 0 0 180)
			(unlocked yes)
			(layer "B.Fab")
			(hide yes)
			(effects
				(font
					(size 1 1)
					(thickness 0.15)
				)
				(justify mirror)
			)
		)
		(property "Val" "100n"
			(at 0 0 180)
			(unlocked yes)
			(layer "B.Fab")
			(hide yes)
			(effects
				(font
					(size 1 1)
					(thickness 0.15)
				)
				(justify mirror)
			)
		)
		(property "License" "Apache-2.0"
			(at 0 0 180)
			(unlocked yes)
			(layer "B.Fab")
			(hide yes)
			(effects
				(font
					(size 1 1)
					(thickness 0.15)
				)
				(justify mirror)
			)
		)
		(property "Author" "Antmicro"
			(at 0 0 180)
			(unlocked yes)
			(layer "B.Fab")
			(hide yes)
			(effects
				(font
					(size 1 1)
					(thickness 0.15)
				)
				(justify mirror)
			)
		)
		(property "Voltage" "50V"
			(at 0 0 180)
			(unlocked yes)
			(layer "B.Fab")
			(hide yes)
			(effects
				(font
					(size 1 1)
					(thickness 0.15)
				)
				(justify mirror)
			)
		)
		(property "Dielectric" "X5R"
			(at 0 0 180)
			(unlocked yes)
			(layer "B.Fab")
			(hide yes)
			(effects
				(font
					(size 1 1)
					(thickness 0.15)
				)
				(justify mirror)
			)
		)
		(sheetname "/Recovery USB/")
		(sheetfile "recovery_usb.kicad_sch")
		(attr smd)
		(fp_poly
			(pts
				(xy -0.925 0.47) (xy -0.925 -0.47) (xy 0.925 -0.47) (xy 0.925 0.47)
			)
			(stroke
				(width 0.05)
				(type default)
			)
			(fill no)
			(layer "B.CrtYd")
		)
		(fp_line
			(start -0.494 -0.248)
			(end -0.494 0.25)
			(stroke
				(width 0.15)
				(type solid)
			)
			(layer "B.Fab")
		)
		(fp_line
			(start -0.494 0.25)
			(end 0.504 0.25)
			(stroke
				(width 0.15)
				(type solid)
			)
			(layer "B.Fab")
		)
		(fp_line
			(start 0.504 -0.248)
			(end -0.494 -0.248)
			(stroke
				(width 0.15)
				(type solid)
			)
			(layer "B.Fab")
		)
		(fp_line
			(start 0.504 0.25)
			(end 0.504 -0.248)
			(stroke
				(width 0.15)
				(type solid)
			)
			(layer "B.Fab")
		)
		(fp_text user "${REFERENCE}"
			(at -0.939 -4.599 0)
			(layer "B.Fab")
			(effects
				(font
					(size 0.7 0.7)
					(thickness 0.15)
				)
				(justify right top mirror)
			)
		)
		(fp_text user "License: Apache-2.0"
			(at -0.939 -5.799 0)
			(layer "B.Fab")
			(effects
				(font
					(size 0.7 0.7)
					(thickness 0.15)
				)
				(justify right top mirror)
			)
		)
		(fp_text user "Author: Antmicro"
			(at -0.939 -3.399 0)
			(layer "B.Fab")
			(effects
				(font
					(size 0.7 0.7)
					(thickness 0.15)
				)
				(justify right top mirror)
			)
		)
		(pad "1" smd roundrect
			(at -0.48 0)
			(size 0.59 0.64)
			(layers "B.Cu" "B.Mask" "B.Paste")
			(roundrect_rratio 0.25)
			(net 5 "+5V")
			(pintype "passive")
		)
		(pad "2" smd roundrect
			(at 0.48 0)
			(size 0.59 0.64)
			(layers "B.Cu" "B.Mask" "B.Paste")
			(roundrect_rratio 0.25)
			(net 1 "GND")
			(pintype "passive")
		)
	)
)
